(kicad_pcb
	(version 20260206)
	(generator "pcbnew")
	(generator_version "10.0")
	(general
		(thickness 1.6)
		(legacy_teardrops no)
	)
	(paper "A4")
	(title_block
		(title "panther-plus-userver — 13130-1b_20150205.brd")
		(comment 1 "Honey Badger (Wiwynn) / footprints 222-229 of 1509")
	)
	(layers
		(0 "F.Cu" signal "TOP")
		(4 "In1.Cu" signal "L2")
		(6 "In2.Cu" signal "L3")
		(8 "In3.Cu" signal "L4")
		(10 "In4.Cu" signal "L5")
		(12 "In5.Cu" signal "L6")
		(14 "In6.Cu" signal "L7")
		(16 "In7.Cu" signal "L8")
		(18 "In8.Cu" signal "L9")
		(20 "In9.Cu" signal "L10")
		(22 "In10.Cu" signal "L11")
		(2 "B.Cu" signal "BOTTOM")
		(9 "F.Adhes" user "F.Adhesive")
		(11 "B.Adhes" user "B.Adhesive")
		(13 "F.Paste" user "Package Geometry/Pastemask Top")
		(15 "B.Paste" user "Package Geometry/Pastemask Bottom")
		(5 "F.SilkS" user "Ref Des/Silkscreen Top")
		(7 "B.SilkS" user "Ref Des/Silkscreen Bottom")
		(1 "F.Mask" user "Board Geometry/Soldermask Top")
		(3 "B.Mask" user "Board Geometry/Soldermask Bottom")
		(17 "Dwgs.User" user "User.Drawings")
		(19 "Cmts.User" user "User.Comments")
		(21 "Eco1.User" user "User.Eco1")
		(23 "Eco2.User" user "User.Eco2")
		(25 "Edge.Cuts" user "Board Geometry/Outline")
		(27 "Margin" user)
		(31 "F.CrtYd" user "Package Geometry/Place Bound Top")
		(29 "B.CrtYd" user "Package Geometry/Place Bound Bottom")
		(35 "F.Fab" user "Ref Des/Assembly Top")
		(33 "B.Fab" user "Ref Des/Assembly Bottom")
	)
	(footprint ""
		(layer "F.Cu")
		(at 197.612 -4.064 90)
		(property "Reference" "C87"
			(at 0 0 90)
			(layer "F.SilkS")
			(hide yes)
			(effects
				(font
					(size 1.27 1.27)
				)
			)
		)
		(property "Value" "SC1U6D3V2KX-GP"
			(at 1.1811 -2.7051 90)
			(unlocked yes)
			(layer "F.Fab")
			(hide yes)
			(effects
				(font
					(size 1.016 1.016)
					(thickness 0.1524)
				)
			)
		)
		(property "Device Type" "C402H22"
			(at 1.1811 -4.2291 90)
			(unlocked yes)
			(layer "F.Fab")
			(hide yes)
			(effects
				(font
					(size 1.016 1.016)
					(thickness 0.1524)
				)
			)
		)
		(duplicate_pad_numbers_are_jumpers no)
		(fp_rect
			(start -0.381 0.7366)
			(end 0.381 -0.7366)
			(stroke
				(width 0)
				(type default)
			)
			(fill no)
			(layer "F.CrtYd")
		)
		(fp_rect
			(start -0.381 0.7366)
			(end 0.381 -0.7366)
			(stroke
				(width 0)
				(type default)
			)
			(fill no)
			(layer "F.Fab")
		)
		(pad "1" smd custom
			(at 0 -0.4572 90)
			(size 0.1143 0.1143)
			(layers "F.Cu" "F.Mask" "F.Paste")
			(net "PV_VTT_DDR_B")
			(options
				(clearance outline)
				(anchor circle)
			)
			(primitives
				(gr_poly
					(pts
						(arc
							(start -0.254 -0.1778)
							(mid -0.239121 -0.213721)
							(end -0.2032 -0.2286)
						)
						(arc
							(start 0.2032 -0.2286)
							(mid 0.239121 -0.213721)
							(end 0.254 -0.1778)
						)
						(arc
							(start 0.254 0.1778)
							(mid 0.239121 0.213721)
							(end 0.2032 0.2286)
						)
						(arc
							(start -0.2032 0.2286)
							(mid -0.239121 0.213721)
							(end -0.254 0.1778)
						)
					)
					(width 0)
					(fill yes)
				)
			)
		)
		(pad "2" smd custom
			(at 0 0.4572 90)
			(size 0.1143 0.1143)
			(layers "F.Cu" "F.Mask" "F.Paste")
			(net "GND")
			(options
				(clearance outline)
				(anchor circle)
			)
			(primitives
				(gr_poly
					(pts
						(arc
							(start -0.254 -0.1778)
							(mid -0.239121 -0.213721)
							(end -0.2032 -0.2286)
						)
						(arc
							(start 0.2032 -0.2286)
							(mid 0.239121 -0.213721)
							(end 0.254 -0.1778)
						)
						(arc
							(start 0.254 0.1778)
							(mid 0.239121 0.213721)
							(end 0.2032 0.2286)
						)
						(arc
							(start -0.2032 0.2286)
							(mid -0.239121 0.213721)
							(end -0.254 0.1778)
						)
					)
					(width 0)
					(fill yes)
				)
			)
		)
	)
	(footprint ""
		(layer "F.Cu")
		(at 7.5184 -22.225 90)
		(property "Reference" "PR116"
			(at 0 0 90)
			(layer "F.SilkS")
			(hide yes)
			(effects
				(font
					(size 1.27 1.27)
				)
			)
		)
		(property "Value" "78K7R2F-GP"
			(at 1.7907 -1.1176 90)
			(unlocked yes)
			(layer "F.Fab")
			(hide yes)
			(effects
				(font
					(size 1.016 1.016)
					(thickness 0.1524)
				)
			)
		)
		(property "Device Type" "R402H16"
			(at 1.7907 -2.6416 90)
			(unlocked yes)
			(layer "F.Fab")
			(hide yes)
			(effects
				(font
					(size 1.016 1.016)
					(thickness 0.1524)
				)
			)
		)
		(duplicate_pad_numbers_are_jumpers no)
		(fp_rect
			(start -0.381 0.8382)
			(end 0.381 -0.8382)
			(stroke
				(width 0)
				(type default)
			)
			(fill no)
			(layer "F.CrtYd")
		)
		(fp_rect
			(start -0.381 0.8382)
			(end 0.381 -0.8382)
			(stroke
				(width 0)
				(type default)
			)
			(fill no)
			(layer "F.Fab")
		)
		(pad "1" smd custom
			(at 0 -0.4318 90)
			(size 0.127 0.127)
			(layers "F.Cu" "F.Mask" "F.Paste")
			(net "AGND_P1V0")
			(options
				(clearance outline)
				(anchor circle)
			)
			(primitives
				(gr_poly
					(pts
						(arc
							(start -0.2032 -0.2794)
							(mid -0.239121 -0.264521)
							(end -0.254 -0.2286)
						)
						(arc
							(start -0.254 0.2286)
							(mid -0.239121 0.264521)
							(end -0.2032 0.2794)
						)
						(arc
							(start 0.2032 0.2794)
							(mid 0.239121 0.264521)
							(end 0.254 0.2286)
						)
						(arc
							(start 0.254 -0.2286)
							(mid 0.239121 -0.264521)
							(end 0.2032 -0.2794)
						)
					)
					(width 0)
					(fill yes)
				)
			)
		)
		(pad "2" smd custom
			(at 0 0.4318 90)
			(size 0.127 0.127)
			(layers "F.Cu" "F.Mask" "F.Paste")
			(net "P1V0_TRIP")
			(options
				(clearance outline)
				(anchor circle)
			)
			(primitives
				(gr_poly
					(pts
						(arc
							(start -0.2032 -0.2794)
							(mid -0.239121 -0.264521)
							(end -0.254 -0.2286)
						)
						(arc
							(start -0.254 0.2286)
							(mid -0.239121 0.264521)
							(end -0.2032 0.2794)
						)
						(arc
							(start 0.2032 0.2794)
							(mid 0.239121 0.264521)
							(end 0.254 0.2286)
						)
						(arc
							(start 0.254 -0.2286)
							(mid 0.239121 -0.264521)
							(end 0.2032 -0.2794)
						)
					)
					(width 0)
					(fill yes)
				)
			)
		)
	)
	(footprint ""
		(layer "F.Cu")
		(at 116.967 -37.354002 90)
		(property "Reference" "PR108"
			(at 0 0 90)
			(layer "F.SilkS")
			(hide yes)
			(effects
				(font
					(size 1.27 1.27)
				)
			)
		)
		(property "Value" "0R2J-2-GP"
			(at 0.064008 -3.993896 90)
			(unlocked yes)
			(layer "F.Fab")
			(hide yes)
			(effects
				(font
					(size 1.016 1.016)
					(thickness 0.1524)
				)
			)
		)
		(property "Device Type" "R402H16"
			(at 0.064008 -5.517896 90)
			(unlocked yes)
			(layer "F.Fab")
			(hide yes)
			(effects
				(font
					(size 1.016 1.016)
					(thickness 0.1524)
				)
			)
		)
		(duplicate_pad_numbers_are_jumpers no)
		(fp_rect
			(start -0.381 0.8382)
			(end 0.381 -0.8382)
			(stroke
				(width 0)
				(type default)
			)
			(fill no)
			(layer "F.CrtYd")
		)
		(fp_rect
			(start -0.381 0.8382)
			(end 0.381 -0.8382)
			(stroke
				(width 0)
				(type default)
			)
			(fill no)
			(layer "F.Fab")
		)
		(pad "1" smd custom
			(at 0 -0.4318 90)
			(size 0.127 0.127)
			(layers "F.Cu" "F.Mask" "F.Paste")
			(net "AVV_VSSCPUVIDSIO_1P03_SENSE")
			(options
				(clearance outline)
				(anchor circle)
			)
			(primitives
				(gr_poly
					(pts
						(arc
							(start -0.2032 -0.2794)
							(mid -0.239121 -0.264521)
							(end -0.254 -0.2286)
						)
						(arc
							(start -0.254 0.2286)
							(mid -0.239121 0.264521)
							(end -0.2032 0.2794)
						)
						(arc
							(start 0.2032 0.2794)
							(mid 0.239121 0.264521)
							(end 0.254 0.2286)
						)
						(arc
							(start 0.254 -0.2286)
							(mid 0.239121 -0.264521)
							(end 0.2032 -0.2794)
						)
					)
					(width 0)
					(fill yes)
				)
			)
		)
		(pad "2" smd custom
			(at 0 0.4318 90)
			(size 0.127 0.127)
			(layers "F.Cu" "F.Mask" "F.Paste")
			(net "VR_PVCCP_RTN")
			(options
				(clearance outline)
				(anchor circle)
			)
			(primitives
				(gr_poly
					(pts
						(arc
							(start -0.2032 -0.2794)
							(mid -0.239121 -0.264521)
							(end -0.254 -0.2286)
						)
						(arc
							(start -0.254 0.2286)
							(mid -0.239121 0.264521)
							(end -0.2032 0.2794)
						)
						(arc
							(start 0.2032 0.2794)
							(mid 0.239121 0.264521)
							(end 0.254 0.2286)
						)
						(arc
							(start 0.254 -0.2286)
							(mid 0.239121 -0.264521)
							(end 0.2032 -0.2794)
						)
					)
					(width 0)
					(fill yes)
				)
			)
		)
	)
	(footprint ""
		(layer "F.Cu")
		(at 194.691 -33.274 180)
		(property "Reference" "PC95"
			(at 0 0 180)
			(layer "F.SilkS")
			(hide yes)
			(effects
				(font
					(size 1.27 1.27)
				)
			)
		)
		(property "Value" "SCD1U25V2KX-2-GP"
			(at 1.8923 -1.2065 180)
			(unlocked yes)
			(layer "F.Fab")
			(hide yes)
			(effects
				(font
					(size 1.016 1.016)
					(thickness 0.1524)
				)
			)
		)
		(property "Device Type" "C402H22"
			(at 1.8923 -2.7305 180)
			(unlocked yes)
			(layer "F.Fab")
			(hide yes)
			(effects
				(font
					(size 1.016 1.016)
					(thickness 0.1524)
				)
			)
		)
		(duplicate_pad_numbers_are_jumpers no)
		(fp_rect
			(start -0.381 0.7366)
			(end 0.381 -0.7366)
			(stroke
				(width 0)
				(type default)
			)
			(fill no)
			(layer "F.CrtYd")
		)
		(fp_rect
			(start -0.381 0.7366)
			(end 0.381 -0.7366)
			(stroke
				(width 0)
				(type default)
			)
			(fill no)
			(layer "F.Fab")
		)
		(pad "1" smd custom
			(at 0 -0.4572 180)
			(size 0.1143 0.1143)
			(layers "F.Cu" "F.Mask" "F.Paste")
			(net "VR_PVDDR_A_BOOT1")
			(options
				(clearance outline)
				(anchor circle)
			)
			(primitives
				(gr_poly
					(pts
						(arc
							(start -0.254 -0.1778)
							(mid -0.239121 -0.213721)
							(end -0.2032 -0.2286)
						)
						(arc
							(start 0.2032 -0.2286)
							(mid 0.239121 -0.213721)
							(end 0.254 -0.1778)
						)
						(arc
							(start 0.254 0.1778)
							(mid 0.239121 0.213721)
							(end 0.2032 0.2286)
						)
						(arc
							(start -0.2032 0.2286)
							(mid -0.239121 0.213721)
							(end -0.254 0.1778)
						)
					)
					(width 0)
					(fill yes)
				)
			)
		)
		(pad "2" smd custom
			(at 0 0.4572 180)
			(size 0.1143 0.1143)
			(layers "F.Cu" "F.Mask" "F.Paste")
			(net "VR_PVDDR_A_PHASE1")
			(options
				(clearance outline)
				(anchor circle)
			)
			(primitives
				(gr_poly
					(pts
						(arc
							(start -0.254 -0.1778)
							(mid -0.239121 -0.213721)
							(end -0.2032 -0.2286)
						)
						(arc
							(start 0.2032 -0.2286)
							(mid 0.239121 -0.213721)
							(end 0.254 -0.1778)
						)
						(arc
							(start 0.254 0.1778)
							(mid 0.239121 0.213721)
							(end 0.2032 0.2286)
						)
						(arc
							(start -0.2032 0.2286)
							(mid -0.239121 0.213721)
							(end -0.254 0.1778)
						)
					)
					(width 0)
					(fill yes)
				)
			)
		)
	)
	(footprint ""
		(layer "F.Cu")
		(at 29.972 -13.335 180)
		(property "Reference" "R421"
			(at 0 0 180)
			(layer "F.SilkS")
			(hide yes)
			(effects
				(font
					(size 1.27 1.27)
				)
			)
		)
		(property "Value" "0R2J-2-GP"
			(at 1.7907 -1.1176 180)
			(unlocked yes)
			(layer "F.Fab")
			(hide yes)
			(effects
				(font
					(size 1.016 1.016)
					(thickness 0.1524)
				)
			)
		)
		(property "Device Type" "R402H16"
			(at 1.7907 -2.6416 180)
			(unlocked yes)
			(layer "F.Fab")
			(hide yes)
			(effects
				(font
					(size 1.016 1.016)
					(thickness 0.1524)
				)
			)
		)
		(duplicate_pad_numbers_are_jumpers no)
		(fp_rect
			(start -0.381 0.8382)
			(end 0.381 -0.8382)
			(stroke
				(width 0)
				(type default)
			)
			(fill no)
			(layer "F.CrtYd")
		)
		(fp_rect
			(start -0.381 0.8382)
			(end 0.381 -0.8382)
			(stroke
				(width 0)
				(type default)
			)
			(fill no)
			(layer "F.Fab")
		)
		(pad "1" smd custom
			(at 0 -0.4318 180)
			(size 0.127 0.127)
			(layers "F.Cu" "F.Mask" "F.Paste")
			(net "BMC_I2C_CLK")
			(options
				(clearance outline)
				(anchor circle)
			)
			(primitives
				(gr_poly
					(pts
						(arc
							(start -0.2032 -0.2794)
							(mid -0.239121 -0.264521)
							(end -0.254 -0.2286)
						)
						(arc
							(start -0.254 0.2286)
							(mid -0.239121 0.264521)
							(end -0.2032 0.2794)
						)
						(arc
							(start 0.2032 0.2794)
							(mid 0.239121 0.264521)
							(end 0.254 0.2286)
						)
						(arc
							(start 0.254 -0.2286)
							(mid 0.239121 -0.264521)
							(end 0.2032 -0.2794)
						)
					)
					(width 0)
					(fill yes)
				)
			)
		)
		(pad "2" smd custom
			(at 0 0.4318 180)
			(size 0.127 0.127)
			(layers "F.Cu" "F.Mask" "F.Paste")
			(net "PCIE_GF_I2C_CLK")
			(options
				(clearance outline)
				(anchor circle)
			)
			(primitives
				(gr_poly
					(pts
						(arc
							(start -0.2032 -0.2794)
							(mid -0.239121 -0.264521)
							(end -0.254 -0.2286)
						)
						(arc
							(start -0.254 0.2286)
							(mid -0.239121 0.264521)
							(end -0.2032 0.2794)
						)
						(arc
							(start 0.2032 0.2794)
							(mid 0.239121 0.264521)
							(end 0.254 0.2286)
						)
						(arc
							(start 0.254 -0.2286)
							(mid 0.239121 -0.264521)
							(end 0.2032 -0.2794)
						)
					)
					(width 0)
					(fill yes)
				)
			)
		)
	)
	(footprint ""
		(layer "F.Cu")
		(at 42.799 -15.494 -90)
		(property "Reference" "R60"
			(at 0 0 270)
			(layer "F.SilkS")
			(hide yes)
			(effects
				(font
					(size 1.27 1.27)
				)
			)
		)
		(property "Value" "2D2R3J-2-GP"
			(at -0.0254 -2.0193 270)
			(unlocked yes)
			(layer "F.Fab")
			(hide yes)
			(effects
				(font
					(size 1.016 1.016)
					(thickness 0.1524)
				)
			)
		)
		(property "Device Type" "R603H22"
			(at -0.0254 -3.5433 270)
			(unlocked yes)
			(layer "F.Fab")
			(hide yes)
			(effects
				(font
					(size 1.016 1.016)
					(thickness 0.1524)
				)
			)
		)
		(duplicate_pad_numbers_are_jumpers no)
		(fp_line
			(start -0.2032 0)
			(end -0.4191 0)
			(stroke
				(width 0.2032)
				(type default)
			)
			(layer "F.SilkS")
		)
		(fp_line
			(start 0.4318 0)
			(end 0.2032 0)
			(stroke
				(width 0.2032)
				(type default)
			)
			(layer "F.SilkS")
		)
		(fp_rect
			(start -0.635 1.1811)
			(end 0.635 -1.1811)
			(stroke
				(width 0)
				(type default)
			)
			(fill no)
			(layer "F.CrtYd")
		)
		(fp_rect
			(start -0.635 1.1811)
			(end 0.635 -1.1811)
			(stroke
				(width 0)
				(type default)
			)
			(fill no)
			(layer "F.Fab")
		)
		(pad "1" smd custom
			(at 0 -0.6604 270)
			(size 0.19685 0.19685)
			(layers "F.Cu" "F.Mask" "F.Paste")
			(net "P3V3_VDD_CLKBUFF_R")
			(options
				(clearance outline)
				(anchor circle)
			)
			(primitives
				(gr_poly
					(pts
						(arc
							(start 0.508 -0.2921)
							(mid 0.478242 -0.363942)
							(end 0.4064 -0.3937)
						)
						(arc
							(start -0.4064 -0.3937)
							(mid -0.478242 -0.363942)
							(end -0.508 -0.2921)
						)
						(arc
							(start -0.508 0.2921)
							(mid -0.478242 0.363942)
							(end -0.4064 0.3937)
						)
						(arc
							(start 0.4064 0.3937)
							(mid 0.478242 0.363942)
							(end 0.508 0.2921)
						)
					)
					(width 0)
					(fill yes)
				)
			)
		)
		(pad "2" smd custom
			(at 0 0.6604 270)
			(size 0.19685 0.19685)
			(layers "F.Cu" "F.Mask" "F.Paste")
			(net "P3V3_VDD_CLKBUFF")
			(options
				(clearance outline)
				(anchor circle)
			)
			(primitives
				(gr_poly
					(pts
						(arc
							(start 0.508 -0.2921)
							(mid 0.478242 -0.363942)
							(end 0.4064 -0.3937)
						)
						(arc
							(start -0.4064 -0.3937)
							(mid -0.478242 -0.363942)
							(end -0.508 -0.2921)
						)
						(arc
							(start -0.508 0.2921)
							(mid -0.478242 0.363942)
							(end -0.4064 0.3937)
						)
						(arc
							(start 0.4064 0.3937)
							(mid 0.478242 0.363942)
							(end 0.508 0.2921)
						)
					)
					(width 0)
					(fill yes)
				)
			)
		)
	)
	(footprint ""
		(layer "F.Cu")
		(at 182.372 -33.5026)
		(property "Reference" "PR140"
			(at 0 0 0)
			(layer "F.SilkS")
			(hide yes)
			(effects
				(font
					(size 1.27 1.27)
				)
			)
		)
		(property "Value" "5K11R2F-L1-GP"
			(at 1.7907 -1.1176 0)
			(unlocked yes)
			(layer "F.Fab")
			(hide yes)
			(effects
				(font
					(size 1.016 1.016)
					(thickness 0.1524)
				)
			)
		)
		(property "Device Type" "R402H16"
			(at 1.7907 -2.6416 0)
			(unlocked yes)
			(layer "F.Fab")
			(hide yes)
			(effects
				(font
					(size 1.016 1.016)
					(thickness 0.1524)
				)
			)
		)
		(duplicate_pad_numbers_are_jumpers no)
		(fp_rect
			(start -0.381 0.8382)
			(end 0.381 -0.8382)
			(stroke
				(width 0)
				(type default)
			)
			(fill no)
			(layer "F.CrtYd")
		)
		(fp_rect
			(start -0.381 0.8382)
			(end 0.381 -0.8382)
			(stroke
				(width 0)
				(type default)
			)
			(fill no)
			(layer "F.Fab")
		)
		(pad "1" smd custom
			(at 0 -0.4318)
			(size 0.127 0.127)
			(layers "F.Cu" "F.Mask" "F.Paste")
			(net "P3V3_STBY")
			(options
				(clearance outline)
				(anchor circle)
			)
			(primitives
				(gr_poly
					(pts
						(arc
							(start -0.2032 -0.2794)
							(mid -0.239121 -0.264521)
							(end -0.254 -0.2286)
						)
						(arc
							(start -0.254 0.2286)
							(mid -0.239121 0.264521)
							(end -0.2032 0.2794)
						)
						(arc
							(start 0.2032 0.2794)
							(mid 0.239121 0.264521)
							(end 0.254 0.2286)
						)
						(arc
							(start 0.254 -0.2286)
							(mid 0.239121 -0.264521)
							(end 0.2032 -0.2794)
						)
					)
					(width 0)
					(fill yes)
				)
			)
		)
		(pad "2" smd custom
			(at 0 0.4318)
			(size 0.127 0.127)
			(layers "F.Cu" "F.Mask" "F.Paste")
			(net "PVCCP_PVNN_VRHOT#")
			(options
				(clearance outline)
				(anchor circle)
			)
			(primitives
				(gr_poly
					(pts
						(arc
							(start -0.2032 -0.2794)
							(mid -0.239121 -0.264521)
							(end -0.254 -0.2286)
						)
						(arc
							(start -0.254 0.2286)
							(mid -0.239121 0.264521)
							(end -0.2032 0.2794)
						)
						(arc
							(start 0.2032 0.2794)
							(mid 0.239121 0.264521)
							(end 0.254 0.2286)
						)
						(arc
							(start 0.254 -0.2286)
							(mid 0.239121 -0.264521)
							(end 0.2032 -0.2794)
						)
					)
					(width 0)
					(fill yes)
				)
			)
		)
	)
	(footprint ""
		(layer "F.Cu")
		(at 29.2354 -54.5084 -90)
		(property "Reference" "PR47"
			(at 0 0 270)
			(layer "F.SilkS")
			(hide yes)
			(effects
				(font
					(size 1.27 1.27)
				)
			)
		)
		(property "Value" "0R2J-2-GP"
			(at 1.7907 -1.1176 270)
			(unlocked yes)
			(layer "F.Fab")
			(hide yes)
			(effects
				(font
					(size 1.016 1.016)
					(thickness 0.1524)
				)
			)
		)
		(property "Device Type" "R402H16"
			(at 1.7907 -2.6416 270)
			(unlocked yes)
			(layer "F.Fab")
			(hide yes)
			(effects
				(font
					(size 1.016 1.016)
					(thickness 0.1524)
				)
			)
		)
		(duplicate_pad_numbers_are_jumpers no)
		(fp_rect
			(start -0.381 0.8382)
			(end 0.381 -0.8382)
			(stroke
				(width 0)
				(type default)
			)
			(fill no)
			(layer "F.CrtYd")
		)
		(fp_rect
			(start -0.381 0.8382)
			(end 0.381 -0.8382)
			(stroke
				(width 0)
				(type default)
			)
			(fill no)
			(layer "F.Fab")
		)
		(pad "1" smd custom
			(at 0 -0.4318 270)
			(size 0.127 0.127)
			(layers "F.Cu" "F.Mask" "F.Paste")
			(net "VR_PVCCP_PHASE")
			(options
				(clearance outline)
				(anchor circle)
			)
			(primitives
				(gr_poly
					(pts
						(arc
							(start -0.2032 -0.2794)
							(mid -0.239121 -0.264521)
							(end -0.254 -0.2286)
						)
						(arc
							(start -0.254 0.2286)
							(mid -0.239121 0.264521)
							(end -0.2032 0.2794)
						)
						(arc
							(start 0.2032 0.2794)
							(mid 0.239121 0.264521)
							(end 0.254 0.2286)
						)
						(arc
							(start 0.254 -0.2286)
							(mid 0.239121 -0.264521)
							(end 0.2032 -0.2794)
						)
					)
					(width 0)
					(fill yes)
				)
			)
		)
		(pad "2" smd custom
			(at 0 0.4318 270)
			(size 0.127 0.127)
			(layers "F.Cu" "F.Mask" "F.Paste")
			(net "VR_PVCCP_BOOT_R")
			(options
				(clearance outline)
				(anchor circle)
			)
			(primitives
				(gr_poly
					(pts
						(arc
							(start -0.2032 -0.2794)
							(mid -0.239121 -0.264521)
							(end -0.254 -0.2286)
						)
						(arc
							(start -0.254 0.2286)
							(mid -0.239121 0.264521)
							(end -0.2032 0.2794)
						)
						(arc
							(start 0.2032 0.2794)
							(mid 0.239121 0.264521)
							(end 0.254 0.2286)
						)
						(arc
							(start 0.254 -0.2286)
							(mid 0.239121 -0.264521)
							(end 0.2032 -0.2794)
						)
					)
					(width 0)
					(fill yes)
				)
			)
		)
	)
)
